# S9S_MB_2U (Grand Teton) — schematic netlist excerpt (pin names and nets, part order shuffled) for the footprints in the layout excerpt that follows; sources: Cadence DE-HDL packaged netlist, KiCad conversion of 03242023_DA0F0TMBIJ0_F0T_Motherboard_J_brd_V01_OCP.brd

R2667  Q_RES  10K 1% CHIP  pkg 0402LF  page 234 : A = P3V3_AUX ; B = SMB_BMC_SWB_BUF_R_SCL
R3061  Q_RES  33.2 1% CHIP  pkg 0402LF  page 241 : A = SMB_SML1_PMBUS_3V3AUX_PCH_SDA ; B = SMB_PMBUS_SML1_ME_SDA

(kicad_pcb
	(version 20260206)
	(generator "pcbnew")
	(generator_version "10.0")
	(general
		(thickness 1.6)
		(legacy_teardrops no)
	)
	(paper "A4")
	(title_block
		(title "03242023_DA0F0TMBIJ0_F0T_Motherboard_J_brd_V01_OCP.brd")
		(comment 1 "Grand Teton / footprints 496-497 of 6105")
	)
	(layers
		(0 "F.Cu" signal "TOP")
		(4 "In1.Cu" signal "GND")
		(6 "In2.Cu" signal "IN1")
		(8 "In3.Cu" signal "GND1")
		(10 "In4.Cu" signal "IN2")
		(12 "In5.Cu" signal "GND2")
		(14 "In6.Cu" signal "IN3")
		(16 "In7.Cu" signal "GND3")
		(18 "In8.Cu" signal "VCC")
		(20 "In9.Cu" signal "VCC1")
		(22 "In10.Cu" signal "GND4")
		(24 "In11.Cu" signal "IN4")
		(26 "In12.Cu" signal "GND5")
		(28 "In13.Cu" signal "IN5")
		(30 "In14.Cu" signal "GND6")
		(32 "In15.Cu" signal "IN6")
		(34 "In16.Cu" signal "GND7")
		(2 "B.Cu" signal "BOTTOM")
		(9 "F.Adhes" user "F.Adhesive")
		(11 "B.Adhes" user "B.Adhesive")
		(13 "F.Paste" user "Package Geometry/Pastemask Top")
		(15 "B.Paste" user "Package Geometry/Pastemask Bottom")
		(5 "F.SilkS" user "Ref Des/Silkscreen Top")
		(7 "B.SilkS" user "Ref Des/Silkscreen Bottom")
		(1 "F.Mask" user "Board Geometry/Soldermask Top")
		(3 "B.Mask" user "Board Geometry/Soldermask Bottom")
		(17 "Dwgs.User" user "User.Drawings")
		(19 "Cmts.User" user "User.Comments")
		(21 "Eco1.User" user "User.Eco1")
		(23 "Eco2.User" user "User.Eco2")
		(25 "Edge.Cuts" user "Board Geometry/Outline")
		(27 "Margin" user)
		(31 "F.CrtYd" user "Package Geometry/Place Bound Top")
		(29 "B.CrtYd" user "Package Geometry/Place Bound Bottom")
		(35 "F.Fab" user "Ref Des/Assembly Top")
		(33 "B.Fab" user "Ref Des/Assembly Bottom")
	)
	(footprint ""
		(layer "F.Cu")
		(at 9.58088 -54.955948)
		(property "Reference" "R3061"
			(at 0 0 0)
			(layer "F.SilkS")
			(hide yes)
			(effects
				(font
					(size 1.27 1.27)
				)
			)
		)
		(property "Value" ""
			(at 0 0 0)
			(layer "F.Fab")
			(effects
				(font
					(size 1.27 1.27)
				)
			)
		)
		(duplicate_pad_numbers_are_jumpers no)
		(fp_line
			(start -0.7874 -0.4064)
			(end 0.7874 -0.4064)
			(stroke
				(width 0.1524)
				(type default)
			)
			(layer "F.SilkS")
		)
		(fp_line
			(start -0.7874 0.4064)
			(end -0.7874 -0.4064)
			(stroke
				(width 0.1524)
				(type default)
			)
			(layer "F.SilkS")
		)
		(fp_line
			(start 0.7874 -0.4064)
			(end 0.7874 0.4064)
			(stroke
				(width 0.1524)
				(type default)
			)
			(layer "F.SilkS")
		)
		(fp_line
			(start 0.7874 0.4064)
			(end -0.7874 0.4064)
			(stroke
				(width 0.1524)
				(type default)
			)
			(layer "F.SilkS")
		)
		(fp_line
			(start -0.67945 -0.305054)
			(end -0.12065 -0.305054)
			(stroke
				(width 0.1)
				(type default)
			)
			(layer "F.Fab")
		)
		(fp_line
			(start -0.67945 0.3048)
			(end -0.67945 -0.305054)
			(stroke
				(width 0.1)
				(type default)
			)
			(layer "F.Fab")
		)
		(fp_line
			(start -0.12065 -0.305054)
			(end -0.12065 -0.2794)
			(stroke
				(width 0.1)
				(type default)
			)
			(layer "F.Fab")
		)
		(fp_line
			(start -0.12065 -0.2794)
			(end 0.12065 -0.2794)
			(stroke
				(width 0.1)
				(type default)
			)
			(layer "F.Fab")
		)
		(fp_line
			(start -0.12065 0.2794)
			(end -0.12065 0.3048)
			(stroke
				(width 0.1)
				(type default)
			)
			(layer "F.Fab")
		)
		(fp_line
			(start -0.12065 0.3048)
			(end -0.67945 0.3048)
			(stroke
				(width 0.1)
				(type default)
			)
			(layer "F.Fab")
		)
		(fp_line
			(start 0.120396 0.2794)
			(end -0.12065 0.2794)
			(stroke
				(width 0.1)
				(type default)
			)
			(layer "F.Fab")
		)
		(fp_line
			(start 0.120396 0.3048)
			(end 0.120396 0.2794)
			(stroke
				(width 0.1)
				(type default)
			)
			(layer "F.Fab")
		)
		(fp_line
			(start 0.12065 -0.3048)
			(end 0.67945 -0.3048)
			(stroke
				(width 0.1)
				(type default)
			)
			(layer "F.Fab")
		)
		(fp_line
			(start 0.12065 -0.2794)
			(end 0.12065 -0.3048)
			(stroke
				(width 0.1)
				(type default)
			)
			(layer "F.Fab")
		)
		(fp_line
			(start 0.67945 -0.3048)
			(end 0.67945 0.3048)
			(stroke
				(width 0.1)
				(type default)
			)
			(layer "F.Fab")
		)
		(fp_line
			(start 0.67945 0.3048)
			(end 0.120396 0.3048)
			(stroke
				(width 0.1)
				(type default)
			)
			(layer "F.Fab")
		)
		(pad "1" smd circle
			(at -0.40005 0)
			(size 0 0)
			(layers "F.Cu" "F.Mask" "F.Paste")
			(net "SMB_SML1_PMBUS_3V3AUX_PCH_SDA")
		)
		(pad "2" smd circle
			(at 0.40005 0)
			(size 0 0)
			(layers "F.Cu" "F.Mask" "F.Paste")
			(net "SMB_PMBUS_SML1_ME_SDA")
		)
	)
	(footprint ""
		(layer "F.Cu")
		(at 164.14115 -432.865276 -90)
		(property "Reference" "R2667"
			(at 0 0 270)
			(layer "F.SilkS")
			(hide yes)
			(effects
				(font
					(size 1.27 1.27)
				)
			)
		)
		(property "Value" ""
			(at 0 0 270)
			(layer "F.Fab")
			(effects
				(font
					(size 1.27 1.27)
				)
			)
		)
		(duplicate_pad_numbers_are_jumpers no)
		(fp_line
			(start -0.7874 0.4064)
			(end -0.7874 -0.4064)
			(stroke
				(width 0.1524)
				(type default)
			)
			(layer "F.SilkS")
		)
		(fp_line
			(start 0.7874 0.4064)
			(end -0.7874 0.4064)
			(stroke
				(width 0.1524)
				(type default)
			)
			(layer "F.SilkS")
		)
		(fp_line
			(start -0.7874 -0.4064)
			(end 0.7874 -0.4064)
			(stroke
				(width 0.1524)
				(type default)
			)
			(layer "F.SilkS")
		)
		(fp_line
			(start 0.7874 -0.4064)
			(end 0.7874 0.4064)
			(stroke
				(width 0.1524)
				(type default)
			)
			(layer "F.SilkS")
		)
		(fp_line
			(start -0.67945 0.3048)
			(end -0.67945 -0.305054)
			(stroke
				(width 0.1)
				(type default)
			)
			(layer "F.Fab")
		)
		(fp_line
			(start -0.12065 0.3048)
			(end -0.67945 0.3048)
			(stroke
				(width 0.1)
				(type default)
			)
			(layer "F.Fab")
		)
		(fp_line
			(start 0.120396 0.3048)
			(end 0.120396 0.2794)
			(stroke
				(width 0.1)
				(type default)
			)
			(layer "F.Fab")
		)
		(fp_line
			(start 0.67945 0.3048)
			(end 0.120396 0.3048)
			(stroke
				(width 0.1)
				(type default)
			)
			(layer "F.Fab")
		)
		(fp_line
			(start -0.12065 0.2794)
			(end -0.12065 0.3048)
			(stroke
				(width 0.1)
				(type default)
			)
			(layer "F.Fab")
		)
		(fp_line
			(start 0.120396 0.2794)
			(end -0.12065 0.2794)
			(stroke
				(width 0.1)
				(type default)
			)
			(layer "F.Fab")
		)
		(fp_line
			(start -0.12065 -0.2794)
			(end 0.12065 -0.2794)
			(stroke
				(width 0.1)
				(type default)
			)
			(layer "F.Fab")
		)
		(fp_line
			(start 0.12065 -0.2794)
			(end 0.12065 -0.3048)
			(stroke
				(width 0.1)
				(type default)
			)
			(layer "F.Fab")
		)
		(fp_line
			(start 0.12065 -0.3048)
			(end 0.67945 -0.3048)
			(stroke
				(width 0.1)
				(type default)
			)
			(layer "F.Fab")
		)
		(fp_line
			(start 0.67945 -0.3048)
			(end 0.67945 0.3048)
			(stroke
				(width 0.1)
				(type default)
			)
			(layer "F.Fab")
		)
		(fp_line
			(start -0.67945 -0.305054)
			(end -0.12065 -0.305054)
			(stroke
				(width 0.1)
				(type default)
			)
			(layer "F.Fab")
		)
		(fp_line
			(start -0.12065 -0.305054)
			(end -0.12065 -0.2794)
			(stroke
				(width 0.1)
				(type default)
			)
			(layer "F.Fab")
		)
		(pad "1" smd circle
			(at -0.40005 0 270)
			(size 0 0)
			(layers "F.Cu" "F.Mask" "F.Paste")
			(net "P3V3_AUX")
		)
		(pad "2" smd circle
			(at 0.40005 0 270)
			(size 0 0)
			(layers "F.Cu" "F.Mask" "F.Paste")
			(net "SMB_BMC_SWB_BUF_R_SCL")
		)
	)
)
